(kicad_pcb
	(version 20260206)
	(generator "pcbnew")
	(generator_version "10.0")
	(general
		(thickness 1.6)
		(legacy_teardrops no)
	)
	(paper "A4")
	(title_block
		(title "v1-chassis-manager — T6M_CM_d_v01_1031_1645.brd")
		(comment 1 "Open CloudServer (Microsoft) / footprints 2404-2413 of 2512")
	)
	(layers
		(0 "F.Cu" signal "TOP")
		(4 "In1.Cu" signal "GND1")
		(6 "In2.Cu" signal "IN1")
		(8 "In3.Cu" signal "VCC1")
		(10 "In4.Cu" signal "VCC2")
		(12 "In5.Cu" signal "GND2")
		(14 "In6.Cu" signal "IN2")
		(16 "In7.Cu" signal "IN3")
		(18 "In8.Cu" signal "GND3")
		(2 "B.Cu" signal "BOTTOM")
		(9 "F.Adhes" user "F.Adhesive")
		(11 "B.Adhes" user "B.Adhesive")
		(13 "F.Paste" user "Package Geometry/Pastemask Top")
		(15 "B.Paste" user "Package Geometry/Pastemask Bottom")
		(5 "F.SilkS" user "Ref Des/Silkscreen Top")
		(7 "B.SilkS" user "Ref Des/Silkscreen Bottom")
		(1 "F.Mask" user "Board Geometry/Soldermask Top")
		(3 "B.Mask" user "Board Geometry/Soldermask Bottom")
		(17 "Dwgs.User" user "User.Drawings")
		(19 "Cmts.User" user "User.Comments")
		(21 "Eco1.User" user "User.Eco1")
		(23 "Eco2.User" user "User.Eco2")
		(25 "Edge.Cuts" user "Board Geometry/Outline")
		(27 "Margin" user)
		(31 "F.CrtYd" user "Package Geometry/Place Bound Top")
		(29 "B.CrtYd" user "Package Geometry/Place Bound Bottom")
		(35 "F.Fab" user "Ref Des/Assembly Top")
		(33 "B.Fab" user "Ref Des/Assembly Bottom")
	)
	(footprint ""
		(layer "B.Cu")
		(at 104.408224 -64.132206 180)
		(property "Reference" "R222"
			(at 4.652518 -0.896874 0)
			(unlocked yes)
			(layer "B.SilkS")
			(effects
				(font
					(size 0.7874 0.5842)
					(thickness 0.1524)
				)
				(justify left mirror)
			)
		)
		(property "Value" ""
			(at 0 0 0)
			(layer "B.Fab")
			(effects
				(font
					(size 1.27 1.27)
				)
				(justify mirror)
			)
		)
		(duplicate_pad_numbers_are_jumpers no)
		(fp_line
			(start 0.7874 0.4064)
			(end 0.7874 -0.4064)
			(stroke
				(width 0.1524)
				(type default)
			)
			(layer "B.SilkS")
		)
		(fp_line
			(start 0.7874 -0.4064)
			(end -0.7874 -0.4064)
			(stroke
				(width 0.1524)
				(type default)
			)
			(layer "B.SilkS")
		)
		(fp_line
			(start -0.7874 0.4064)
			(end 0.7874 0.4064)
			(stroke
				(width 0.1524)
				(type default)
			)
			(layer "B.SilkS")
		)
		(fp_line
			(start -0.7874 -0.4064)
			(end -0.7874 0.4064)
			(stroke
				(width 0.1524)
				(type default)
			)
			(layer "B.SilkS")
		)
		(fp_poly
			(pts
				(xy 0.508 0.2794) (xy 0.508 0.2286) (xy 0.635 0.2286) (xy 0.635 -0.254) (xy 0.5334 -0.254) (xy 0.5334 -0.2794)
				(xy -0.5334 -0.2794) (xy -0.5334 -0.254) (xy -0.635 -0.254) (xy -0.635 0.254) (xy -0.5334 0.254)
				(xy -0.5334 0.2794)
			)
			(stroke
				(width 0)
				(type default)
			)
			(fill no)
			(layer "B.CrtYd")
		)
		(pad "1" smd rect
			(at -0.40005 0)
			(size 0.4572 0.508)
			(layers "B.Cu" "B.Mask" "B.Paste")
			(net "XDP_CPU_NODE1_PG_RST_R")
		)
		(pad "2" smd rect
			(at 0.40005 0)
			(size 0.4572 0.508)
			(layers "B.Cu" "B.Mask" "B.Paste")
			(net "FM_CPU_NODE1_XDP_PG_RST")
		)
	)
	(footprint ""
		(layer "B.Cu")
		(at 128.889252 -141.45895)
		(property "Reference" "C199"
			(at 3.37566 -0.494538 0)
			(unlocked yes)
			(layer "B.SilkS")
			(effects
				(font
					(size 0.7874 0.5842)
					(thickness 0.1524)
				)
				(justify mirror)
			)
		)
		(property "Value" ""
			(at 0 0 0)
			(layer "B.Fab")
			(effects
				(font
					(size 1.27 1.27)
				)
				(justify mirror)
			)
		)
		(duplicate_pad_numbers_are_jumpers no)
		(fp_line
			(start -1.2954 -0.5842)
			(end -1.2954 0.5842)
			(stroke
				(width 0.1524)
				(type default)
			)
			(layer "B.SilkS")
		)
		(fp_line
			(start -1.2954 0.5842)
			(end 1.2954 0.5842)
			(stroke
				(width 0.1524)
				(type default)
			)
			(layer "B.SilkS")
		)
		(fp_line
			(start 0 -0.5842)
			(end 0 0.5842)
			(stroke
				(width 0.1524)
				(type default)
			)
			(layer "B.SilkS")
		)
		(fp_line
			(start 1.2954 -0.5842)
			(end -1.2954 -0.5842)
			(stroke
				(width 0.1524)
				(type default)
			)
			(layer "B.SilkS")
		)
		(fp_line
			(start 1.2954 0.5842)
			(end 1.2954 -0.5842)
			(stroke
				(width 0.1524)
				(type default)
			)
			(layer "B.SilkS")
		)
		(fp_poly
			(pts
				(xy -0.8636 -0.4572) (xy -0.8636 -0.3556) (xy -1.143 -0.3556) (xy -1.143 0.3556) (xy -0.8636 0.3556)
				(xy -0.8636 0.4572) (xy 0.8636 0.4572) (xy 0.8636 0.3556) (xy 1.143 0.3556) (xy 1.143 -0.3556) (xy 0.8636 -0.3556)
				(xy 0.8636 -0.4572)
			)
			(stroke
				(width 0)
				(type default)
			)
			(fill no)
			(layer "B.CrtYd")
		)
		(fp_line
			(start -0.884936 -0.504952)
			(end -0.884936 0.504952)
			(stroke
				(width 0.1)
				(type default)
			)
			(layer "B.Fab")
		)
		(fp_line
			(start -0.884936 0.504952)
			(end 0.884936 0.504952)
			(stroke
				(width 0.1)
				(type default)
			)
			(layer "B.Fab")
		)
		(fp_line
			(start 0.884936 -0.504952)
			(end -0.884936 -0.504952)
			(stroke
				(width 0.1)
				(type default)
			)
			(layer "B.Fab")
		)
		(fp_line
			(start 0.884936 0.504952)
			(end 0.884936 -0.504952)
			(stroke
				(width 0.1)
				(type default)
			)
			(layer "B.Fab")
		)
		(pad "1" smd rect
			(at -0.7366 0 90)
			(size 0.7112 0.8128)
			(layers "B.Cu" "B.Mask" "B.Paste")
			(net "P1V0_NODE1")
		)
		(pad "2" smd rect
			(at 0.7366 0 90)
			(size 0.7112 0.8128)
			(layers "B.Cu" "B.Mask" "B.Paste")
			(net "GND")
		)
	)
	(footprint ""
		(layer "B.Cu")
		(at 49.38776 -181.984142 -90)
		(property "Reference" "C609"
			(at 3.610356 10.422128 270)
			(unlocked yes)
			(layer "B.SilkS")
			(effects
				(font
					(size 0.7874 0.5842)
					(thickness 0.1524)
				)
				(justify left mirror)
			)
		)
		(property "Value" ""
			(at 0 0 90)
			(layer "B.Fab")
			(effects
				(font
					(size 1.27 1.27)
				)
				(justify mirror)
			)
		)
		(duplicate_pad_numbers_are_jumpers no)
		(fp_line
			(start -0.7874 0.4064)
			(end 0.7874 0.4064)
			(stroke
				(width 0.1524)
				(type default)
			)
			(layer "B.SilkS")
		)
		(fp_line
			(start 0.7874 0.4064)
			(end 0.7874 -0.4064)
			(stroke
				(width 0.1524)
				(type default)
			)
			(layer "B.SilkS")
		)
		(fp_line
			(start 0 0.381)
			(end 0 -0.381)
			(stroke
				(width 0.1524)
				(type default)
			)
			(layer "B.SilkS")
		)
		(fp_line
			(start -0.7874 -0.4064)
			(end -0.7874 0.4064)
			(stroke
				(width 0.1524)
				(type default)
			)
			(layer "B.SilkS")
		)
		(fp_line
			(start 0.7874 -0.4064)
			(end -0.7874 -0.4064)
			(stroke
				(width 0.1524)
				(type default)
			)
			(layer "B.SilkS")
		)
		(fp_poly
			(pts
				(xy 0.5334 0.254) (xy 0.635 0.254) (xy 0.635 0.2286) (xy 0.635 -0.254) (xy 0.5334 -0.254) (xy 0.5334 -0.2794)
				(xy -0.5334 -0.2794) (xy -0.5334 -0.254) (xy -0.635 -0.254) (xy -0.635 0.254) (xy -0.5334 0.254)
				(xy -0.5334 0.2794) (xy 0.508 0.2794) (xy 0.5334 0.2794)
			)
			(stroke
				(width 0)
				(type default)
			)
			(fill no)
			(layer "B.CrtYd")
		)
		(pad "1" smd rect
			(at -0.40005 0 90)
			(size 0.4572 0.508)
			(layers "B.Cu" "B.Mask" "B.Paste")
			(net "PSU4_DC_OK_R_BUF")
		)
		(pad "2" smd rect
			(at 0.40005 0 90)
			(size 0.4572 0.508)
			(layers "B.Cu" "B.Mask" "B.Paste")
			(net "GND")
		)
	)
	(footprint ""
		(layer "B.Cu")
		(at 69.268086 -132.677662 180)
		(property "Reference" "C290"
			(at 36.554664 -53.682646 0)
			(unlocked yes)
			(layer "B.SilkS")
			(effects
				(font
					(size 0.7874 0.5842)
					(thickness 0.1524)
				)
				(justify left mirror)
			)
		)
		(property "Value" ""
			(at 0 0 0)
			(layer "B.Fab")
			(effects
				(font
					(size 1.27 1.27)
				)
				(justify mirror)
			)
		)
		(duplicate_pad_numbers_are_jumpers no)
		(fp_line
			(start 0.7874 0.4064)
			(end 0.7874 -0.4064)
			(stroke
				(width 0.1524)
				(type default)
			)
			(layer "B.SilkS")
		)
		(fp_line
			(start 0.7874 -0.4064)
			(end -0.7874 -0.4064)
			(stroke
				(width 0.1524)
				(type default)
			)
			(layer "B.SilkS")
		)
		(fp_line
			(start 0 0.381)
			(end 0 -0.381)
			(stroke
				(width 0.1524)
				(type default)
			)
			(layer "B.SilkS")
		)
		(fp_line
			(start -0.7874 0.4064)
			(end 0.7874 0.4064)
			(stroke
				(width 0.1524)
				(type default)
			)
			(layer "B.SilkS")
		)
		(fp_line
			(start -0.7874 -0.4064)
			(end -0.7874 0.4064)
			(stroke
				(width 0.1524)
				(type default)
			)
			(layer "B.SilkS")
		)
		(fp_poly
			(pts
				(xy 0.5334 0.254) (xy 0.635 0.254) (xy 0.635 0.2286) (xy 0.635 -0.254) (xy 0.5334 -0.254) (xy 0.5334 -0.2794)
				(xy -0.5334 -0.2794) (xy -0.5334 -0.254) (xy -0.635 -0.254) (xy -0.635 0.254) (xy -0.5334 0.254)
				(xy -0.5334 0.2794) (xy 0.508 0.2794) (xy 0.5334 0.2794)
			)
			(stroke
				(width 0)
				(type default)
			)
			(fill no)
			(layer "B.CrtYd")
		)
		(pad "1" smd rect
			(at -0.40005 0)
			(size 0.4572 0.508)
			(layers "B.Cu" "B.Mask" "B.Paste")
			(net "P1V26_BMC_NODE1")
		)
		(pad "2" smd rect
			(at 0.40005 0)
			(size 0.4572 0.508)
			(layers "B.Cu" "B.Mask" "B.Paste")
			(net "GND")
		)
	)
	(footprint ""
		(layer "B.Cu")
		(at 57.838848 -76.50353 90)
		(property "Reference" "C45"
			(at -31.836106 -14.474698 270)
			(unlocked yes)
			(layer "B.SilkS")
			(effects
				(font
					(size 0.7874 0.5842)
					(thickness 0.1524)
				)
				(justify left mirror)
			)
		)
		(property "Value" ""
			(at 0 0 90)
			(layer "B.Fab")
			(effects
				(font
					(size 1.27 1.27)
				)
				(justify mirror)
			)
		)
		(duplicate_pad_numbers_are_jumpers no)
		(fp_line
			(start 0.7874 -0.4064)
			(end -0.7874 -0.4064)
			(stroke
				(width 0.1524)
				(type default)
			)
			(layer "B.SilkS")
		)
		(fp_line
			(start -0.7874 -0.4064)
			(end -0.7874 0.4064)
			(stroke
				(width 0.1524)
				(type default)
			)
			(layer "B.SilkS")
		)
		(fp_line
			(start 0 0.381)
			(end 0 -0.381)
			(stroke
				(width 0.1524)
				(type default)
			)
			(layer "B.SilkS")
		)
		(fp_line
			(start 0.7874 0.4064)
			(end 0.7874 -0.4064)
			(stroke
				(width 0.1524)
				(type default)
			)
			(layer "B.SilkS")
		)
		(fp_line
			(start -0.7874 0.4064)
			(end 0.7874 0.4064)
			(stroke
				(width 0.1524)
				(type default)
			)
			(layer "B.SilkS")
		)
		(fp_poly
			(pts
				(xy 0.5334 0.254) (xy 0.635 0.254) (xy 0.635 0.2286) (xy 0.635 -0.254) (xy 0.5334 -0.254) (xy 0.5334 -0.2794)
				(xy -0.5334 -0.2794) (xy -0.5334 -0.254) (xy -0.635 -0.254) (xy -0.635 0.254) (xy -0.5334 0.254)
				(xy -0.5334 0.2794) (xy 0.508 0.2794) (xy 0.5334 0.2794)
			)
			(stroke
				(width 0)
				(type default)
			)
			(fill no)
			(layer "B.CrtYd")
		)
		(pad "1" smd rect
			(at -0.40005 0 270)
			(size 0.4572 0.508)
			(layers "B.Cu" "B.Mask" "B.Paste")
			(net "P1V05_NODE1")
		)
		(pad "2" smd rect
			(at 0.40005 0 270)
			(size 0.4572 0.508)
			(layers "B.Cu" "B.Mask" "B.Paste")
			(net "GND")
		)
	)
	(footprint ""
		(layer "B.Cu")
		(at 165.011608 -184.067196 180)
		(property "Reference" "R1307"
			(at -7.505192 9.987534 0)
			(unlocked yes)
			(layer "B.SilkS")
			(effects
				(font
					(size 0.7874 0.5842)
					(thickness 0.1524)
				)
				(justify left mirror)
			)
		)
		(property "Value" ""
			(at 0 0 0)
			(layer "B.Fab")
			(effects
				(font
					(size 1.27 1.27)
				)
				(justify mirror)
			)
		)
		(duplicate_pad_numbers_are_jumpers no)
		(fp_line
			(start 0.7874 0.4064)
			(end 0.7874 -0.4064)
			(stroke
				(width 0.1524)
				(type default)
			)
			(layer "B.SilkS")
		)
		(fp_line
			(start 0.7874 -0.4064)
			(end -0.7874 -0.4064)
			(stroke
				(width 0.1524)
				(type default)
			)
			(layer "B.SilkS")
		)
		(fp_line
			(start -0.7874 0.4064)
			(end 0.7874 0.4064)
			(stroke
				(width 0.1524)
				(type default)
			)
			(layer "B.SilkS")
		)
		(fp_line
			(start -0.7874 -0.4064)
			(end -0.7874 0.4064)
			(stroke
				(width 0.1524)
				(type default)
			)
			(layer "B.SilkS")
		)
		(fp_poly
			(pts
				(xy 0.508 0.2794) (xy 0.508 0.2286) (xy 0.635 0.2286) (xy 0.635 -0.254) (xy 0.5334 -0.254) (xy 0.5334 -0.2794)
				(xy -0.5334 -0.2794) (xy -0.5334 -0.254) (xy -0.635 -0.254) (xy -0.635 0.254) (xy -0.5334 0.254)
				(xy -0.5334 0.2794)
			)
			(stroke
				(width 0)
				(type default)
			)
			(fill no)
			(layer "B.CrtYd")
		)
		(pad "1" smd rect
			(at -0.40005 0)
			(size 0.4572 0.508)
			(layers "B.Cu" "B.Mask" "B.Paste")
			(net "P3V3_NODE1")
		)
		(pad "2" smd rect
			(at 0.40005 0)
			(size 0.4572 0.508)
			(layers "B.Cu" "B.Mask" "B.Paste")
			(net "N54365776")
		)
	)
	(footprint ""
		(layer "B.Cu")
		(at 125.892052 -146.20875 180)
		(property "Reference" "C882"
			(at 3.260598 3.330194 0)
			(unlocked yes)
			(layer "B.SilkS")
			(effects
				(font
					(size 0.7874 0.5842)
					(thickness 0.1524)
				)
				(justify left mirror)
			)
		)
		(property "Value" ""
			(at 0 0 0)
			(layer "B.Fab")
			(effects
				(font
					(size 1.27 1.27)
				)
				(justify mirror)
			)
		)
		(duplicate_pad_numbers_are_jumpers no)
		(fp_line
			(start 0.7874 0.4064)
			(end 0.7874 -0.4064)
			(stroke
				(width 0.1524)
				(type default)
			)
			(layer "B.SilkS")
		)
		(fp_line
			(start 0.7874 -0.4064)
			(end -0.7874 -0.4064)
			(stroke
				(width 0.1524)
				(type default)
			)
			(layer "B.SilkS")
		)
		(fp_line
			(start 0 0.381)
			(end 0 -0.381)
			(stroke
				(width 0.1524)
				(type default)
			)
			(layer "B.SilkS")
		)
		(fp_line
			(start -0.7874 0.4064)
			(end 0.7874 0.4064)
			(stroke
				(width 0.1524)
				(type default)
			)
			(layer "B.SilkS")
		)
		(fp_line
			(start -0.7874 -0.4064)
			(end -0.7874 0.4064)
			(stroke
				(width 0.1524)
				(type default)
			)
			(layer "B.SilkS")
		)
		(fp_poly
			(pts
				(xy 0.5334 0.254) (xy 0.635 0.254) (xy 0.635 0.2286) (xy 0.635 -0.254) (xy 0.5334 -0.254) (xy 0.5334 -0.2794)
				(xy -0.5334 -0.2794) (xy -0.5334 -0.254) (xy -0.635 -0.254) (xy -0.635 0.254) (xy -0.5334 0.254)
				(xy -0.5334 0.2794) (xy 0.508 0.2794) (xy 0.5334 0.2794)
			)
			(stroke
				(width 0)
				(type default)
			)
			(fill no)
			(layer "B.CrtYd")
		)
		(pad "1" smd rect
			(at -0.40005 0)
			(size 0.4572 0.508)
			(layers "B.Cu" "B.Mask" "B.Paste")
			(net "P1V538_BMC_NODE1")
		)
		(pad "2" smd rect
			(at 0.40005 0)
			(size 0.4572 0.508)
			(layers "B.Cu" "B.Mask" "B.Paste")
			(net "GND")
		)
	)
	(footprint ""
		(layer "B.Cu")
		(at 65.079372 -80.514698 90)
		(property "Reference" "C66"
			(at -32.158686 -14.55039 270)
			(unlocked yes)
			(layer "B.SilkS")
			(effects
				(font
					(size 0.7874 0.5842)
					(thickness 0.1524)
				)
				(justify left mirror)
			)
		)
		(property "Value" ""
			(at 0 0 90)
			(layer "B.Fab")
			(effects
				(font
					(size 1.27 1.27)
				)
				(justify mirror)
			)
		)
		(duplicate_pad_numbers_are_jumpers no)
		(fp_line
			(start 0.7874 -0.4064)
			(end -0.7874 -0.4064)
			(stroke
				(width 0.1524)
				(type default)
			)
			(layer "B.SilkS")
		)
		(fp_line
			(start -0.7874 -0.4064)
			(end -0.7874 0.4064)
			(stroke
				(width 0.1524)
				(type default)
			)
			(layer "B.SilkS")
		)
		(fp_line
			(start 0 0.381)
			(end 0 -0.381)
			(stroke
				(width 0.1524)
				(type default)
			)
			(layer "B.SilkS")
		)
		(fp_line
			(start 0.7874 0.4064)
			(end 0.7874 -0.4064)
			(stroke
				(width 0.1524)
				(type default)
			)
			(layer "B.SilkS")
		)
		(fp_line
			(start -0.7874 0.4064)
			(end 0.7874 0.4064)
			(stroke
				(width 0.1524)
				(type default)
			)
			(layer "B.SilkS")
		)
		(fp_poly
			(pts
				(xy 0.5334 0.254) (xy 0.635 0.254) (xy 0.635 0.2286) (xy 0.635 -0.254) (xy 0.5334 -0.254) (xy 0.5334 -0.2794)
				(xy -0.5334 -0.2794) (xy -0.5334 -0.254) (xy -0.635 -0.254) (xy -0.635 0.254) (xy -0.5334 0.254)
				(xy -0.5334 0.2794) (xy 0.508 0.2794) (xy 0.5334 0.2794)
			)
			(stroke
				(width 0)
				(type default)
			)
			(fill no)
			(layer "B.CrtYd")
		)
		(pad "1" smd rect
			(at -0.40005 0 270)
			(size 0.4572 0.508)
			(layers "B.Cu" "B.Mask" "B.Paste")
			(net "PV_VCCP_NODE1")
		)
		(pad "2" smd rect
			(at 0.40005 0 270)
			(size 0.4572 0.508)
			(layers "B.Cu" "B.Mask" "B.Paste")
			(net "GND")
		)
	)
	(footprint ""
		(layer "B.Cu")
		(at 114.701574 -109.930692 180)
		(property "Reference" "PC121"
			(at -5.729732 -0.120904 0)
			(unlocked yes)
			(layer "B.SilkS")
			(effects
				(font
					(size 0.7874 0.5842)
					(thickness 0.1524)
				)
				(justify left mirror)
			)
		)
		(property "Value" ""
			(at 0 0 0)
			(layer "B.Fab")
			(effects
				(font
					(size 1.27 1.27)
				)
				(justify mirror)
			)
		)
		(duplicate_pad_numbers_are_jumpers no)
		(fp_line
			(start 1.905 0.8636)
			(end 1.905 -0.8636)
			(stroke
				(width 0.1524)
				(type default)
			)
			(layer "B.SilkS")
		)
		(fp_line
			(start 1.905 -0.8636)
			(end -1.905 -0.8636)
			(stroke
				(width 0.1524)
				(type default)
			)
			(layer "B.SilkS")
		)
		(fp_line
			(start 0 0.8382)
			(end 0 -0.8382)
			(stroke
				(width 0.1524)
				(type default)
			)
			(layer "B.SilkS")
		)
		(fp_line
			(start -1.905 0.8636)
			(end 1.905 0.8636)
			(stroke
				(width 0.1524)
				(type default)
			)
			(layer "B.SilkS")
		)
		(fp_line
			(start -1.905 -0.8636)
			(end -1.905 0.8636)
			(stroke
				(width 0.1524)
				(type default)
			)
			(layer "B.SilkS")
		)
		(fp_rect
			(start 1.524 0.7366)
			(end -1.524 -0.7366)
			(stroke
				(width 0)
				(type default)
			)
			(fill no)
			(layer "B.CrtYd")
		)
		(pad "1" smd rect
			(at -0.94996 0)
			(size 1.1176 1.3716)
			(layers "B.Cu" "B.Mask" "B.Paste")
			(net "GND")
		)
		(pad "2" smd rect
			(at 0.94996 0)
			(size 1.1176 1.3716)
			(layers "B.Cu" "B.Mask" "B.Paste")
			(net "PV_VCCP_NODE1")
		)
	)
	(footprint ""
		(layer "B.Cu")
		(at 41.48582 -150.22449 90)
		(property "Reference" "C395"
			(at 7.986014 -11.2649 270)
			(unlocked yes)
			(layer "B.SilkS")
			(effects
				(font
					(size 0.7874 0.5842)
					(thickness 0.1524)
				)
				(justify left mirror)
			)
		)
		(property "Value" ""
			(at 0 0 90)
			(layer "B.Fab")
			(effects
				(font
					(size 1.27 1.27)
				)
				(justify mirror)
			)
		)
		(duplicate_pad_numbers_are_jumpers no)
		(fp_line
			(start 0.7874 -0.4064)
			(end -0.7874 -0.4064)
			(stroke
				(width 0.1524)
				(type default)
			)
			(layer "B.SilkS")
		)
		(fp_line
			(start -0.7874 -0.4064)
			(end -0.7874 0.4064)
			(stroke
				(width 0.1524)
				(type default)
			)
			(layer "B.SilkS")
		)
		(fp_line
			(start 0 0.381)
			(end 0 -0.381)
			(stroke
				(width 0.1524)
				(type default)
			)
			(layer "B.SilkS")
		)
		(fp_line
			(start 0.7874 0.4064)
			(end 0.7874 -0.4064)
			(stroke
				(width 0.1524)
				(type default)
			)
			(layer "B.SilkS")
		)
		(fp_line
			(start -0.7874 0.4064)
			(end 0.7874 0.4064)
			(stroke
				(width 0.1524)
				(type default)
			)
			(layer "B.SilkS")
		)
		(fp_poly
			(pts
				(xy 0.5334 0.254) (xy 0.635 0.254) (xy 0.635 0.2286) (xy 0.635 -0.254) (xy 0.5334 -0.254) (xy 0.5334 -0.2794)
				(xy -0.5334 -0.2794) (xy -0.5334 -0.254) (xy -0.635 -0.254) (xy -0.635 0.254) (xy -0.5334 0.254)
				(xy -0.5334 0.2794) (xy 0.508 0.2794) (xy 0.5334 0.2794)
			)
			(stroke
				(width 0)
				(type default)
			)
			(fill no)
			(layer "B.CrtYd")
		)
		(pad "1" smd rect
			(at -0.40005 0 270)
			(size 0.4572 0.508)
			(layers "B.Cu" "B.Mask" "B.Paste")
			(net "P3V3_NODE1")
		)
		(pad "2" smd rect
			(at 0.40005 0 270)
			(size 0.4572 0.508)
			(layers "B.Cu" "B.Mask" "B.Paste")
			(net "GND")
		)
	)
)
